(kicad_pcb
	(version 20260206)
	(generator "pcbnew")
	(generator_version "10.0")
	(general
		(thickness 1.6)
		(legacy_teardrops no)
	)
	(paper "A4")
	(title_block
		(title "04192023_DAF0TMB3IC0_F0TG_MB_C_brd_V02_OCP.brd")
		(comment 1 "Grand Teton / footprints 7074-7080 of 8354")
	)
	(layers
		(0 "F.Cu" signal "TOP")
		(4 "In1.Cu" signal "GND")
		(6 "In2.Cu" signal "IN1")
		(8 "In3.Cu" signal "GND1")
		(10 "In4.Cu" signal "IN2")
		(12 "In5.Cu" signal "GND2")
		(14 "In6.Cu" signal "IN3")
		(16 "In7.Cu" signal "GND3")
		(18 "In8.Cu" signal "VCC")
		(20 "In9.Cu" signal "VCC1")
		(22 "In10.Cu" signal "GND4")
		(24 "In11.Cu" signal "IN4")
		(26 "In12.Cu" signal "GND5")
		(28 "In13.Cu" signal "IN5")
		(30 "In14.Cu" signal "GND6")
		(32 "In15.Cu" signal "IN6")
		(34 "In16.Cu" signal "GND7")
		(2 "B.Cu" signal "BOTTOM")
		(9 "F.Adhes" user "F.Adhesive")
		(11 "B.Adhes" user "B.Adhesive")
		(13 "F.Paste" user "Package Geometry/Pastemask Top")
		(15 "B.Paste" user "Package Geometry/Pastemask Bottom")
		(5 "F.SilkS" user "Ref Des/Silkscreen Top")
		(7 "B.SilkS" user "Ref Des/Silkscreen Bottom")
		(1 "F.Mask" user "Board Geometry/Soldermask Top")
		(3 "B.Mask" user "Board Geometry/Soldermask Bottom")
		(17 "Dwgs.User" user "User.Drawings")
		(19 "Cmts.User" user "User.Comments")
		(21 "Eco1.User" user "User.Eco1")
		(23 "Eco2.User" user "User.Eco2")
		(25 "Edge.Cuts" user "Board Geometry/Outline")
		(27 "Margin" user)
		(31 "F.CrtYd" user "Package Geometry/Place Bound Top")
		(29 "B.CrtYd" user "Package Geometry/Place Bound Bottom")
		(35 "F.Fab" user "Ref Des/Assembly Top")
		(33 "B.Fab" user "Ref Des/Assembly Bottom")
	)
	(footprint ""
		(layer "B.Cu")
		(at 338.830158 -309.214012 90)
		(property "Reference" "R392"
			(at 0 0 90)
			(layer "B.SilkS")
			(hide yes)
			(effects
				(font
					(size 1.27 1.27)
				)
				(justify mirror)
			)
		)
		(property "Value" ""
			(at 0 0 90)
			(layer "B.Fab")
			(effects
				(font
					(size 1.27 1.27)
				)
				(justify mirror)
			)
		)
		(duplicate_pad_numbers_are_jumpers no)
		(fp_line
			(start 0.7874 -0.4064)
			(end -0.7874 -0.4064)
			(stroke
				(width 0.1524)
				(type default)
			)
			(layer "B.SilkS")
		)
		(fp_line
			(start -0.7874 -0.4064)
			(end -0.7874 0.4064)
			(stroke
				(width 0.1524)
				(type default)
			)
			(layer "B.SilkS")
		)
		(fp_line
			(start 0.7874 0.4064)
			(end 0.7874 -0.4064)
			(stroke
				(width 0.1524)
				(type default)
			)
			(layer "B.SilkS")
		)
		(fp_line
			(start -0.7874 0.4064)
			(end 0.7874 0.4064)
			(stroke
				(width 0.1524)
				(type default)
			)
			(layer "B.SilkS")
		)
		(fp_line
			(start 0.67945 -0.305054)
			(end 0.12065 -0.305054)
			(stroke
				(width 0.1)
				(type default)
			)
			(layer "B.Fab")
		)
		(fp_line
			(start 0.12065 -0.305054)
			(end 0.12065 -0.2794)
			(stroke
				(width 0.1)
				(type default)
			)
			(layer "B.Fab")
		)
		(fp_line
			(start -0.12065 -0.3048)
			(end -0.67945 -0.3048)
			(stroke
				(width 0.1)
				(type default)
			)
			(layer "B.Fab")
		)
		(fp_line
			(start -0.67945 -0.3048)
			(end -0.67945 0.3048)
			(stroke
				(width 0.1)
				(type default)
			)
			(layer "B.Fab")
		)
		(fp_line
			(start 0.12065 -0.2794)
			(end -0.12065 -0.2794)
			(stroke
				(width 0.1)
				(type default)
			)
			(layer "B.Fab")
		)
		(fp_line
			(start -0.12065 -0.2794)
			(end -0.12065 -0.3048)
			(stroke
				(width 0.1)
				(type default)
			)
			(layer "B.Fab")
		)
		(fp_line
			(start 0.12065 0.2794)
			(end 0.12065 0.3048)
			(stroke
				(width 0.1)
				(type default)
			)
			(layer "B.Fab")
		)
		(fp_line
			(start -0.120396 0.2794)
			(end 0.12065 0.2794)
			(stroke
				(width 0.1)
				(type default)
			)
			(layer "B.Fab")
		)
		(fp_line
			(start 0.67945 0.3048)
			(end 0.67945 -0.305054)
			(stroke
				(width 0.1)
				(type default)
			)
			(layer "B.Fab")
		)
		(fp_line
			(start 0.12065 0.3048)
			(end 0.67945 0.3048)
			(stroke
				(width 0.1)
				(type default)
			)
			(layer "B.Fab")
		)
		(fp_line
			(start -0.120396 0.3048)
			(end -0.120396 0.2794)
			(stroke
				(width 0.1)
				(type default)
			)
			(layer "B.Fab")
		)
		(fp_line
			(start -0.67945 0.3048)
			(end -0.120396 0.3048)
			(stroke
				(width 0.1)
				(type default)
			)
			(layer "B.Fab")
		)
		(pad "1" smd circle
			(at 0.40005 0 270)
			(size 0 0)
			(layers "B.Cu" "B.Mask" "B.Paste")
			(net "PVDD18_S5_P0")
		)
		(pad "2" smd circle
			(at -0.40005 0 270)
			(size 0 0)
			(layers "B.Cu" "B.Mask" "B.Paste")
			(net "CPU0_SA0")
		)
	)
	(footprint ""
		(layer "B.Cu")
		(at 238.379 -234.061 90)
		(property "Reference" "R1161"
			(at 0 0 90)
			(layer "B.SilkS")
			(hide yes)
			(effects
				(font
					(size 1.27 1.27)
				)
				(justify mirror)
			)
		)
		(property "Value" ""
			(at 0 0 90)
			(layer "B.Fab")
			(effects
				(font
					(size 1.27 1.27)
				)
				(justify mirror)
			)
		)
		(duplicate_pad_numbers_are_jumpers no)
		(fp_line
			(start 0.7874 -0.4064)
			(end -0.7874 -0.4064)
			(stroke
				(width 0.1524)
				(type default)
			)
			(layer "B.SilkS")
		)
		(fp_line
			(start -0.7874 -0.4064)
			(end -0.7874 0.4064)
			(stroke
				(width 0.1524)
				(type default)
			)
			(layer "B.SilkS")
		)
		(fp_line
			(start 0.7874 0.4064)
			(end 0.7874 -0.4064)
			(stroke
				(width 0.1524)
				(type default)
			)
			(layer "B.SilkS")
		)
		(fp_line
			(start -0.7874 0.4064)
			(end 0.7874 0.4064)
			(stroke
				(width 0.1524)
				(type default)
			)
			(layer "B.SilkS")
		)
		(fp_line
			(start 0.67945 -0.305054)
			(end 0.12065 -0.305054)
			(stroke
				(width 0.1)
				(type default)
			)
			(layer "B.Fab")
		)
		(fp_line
			(start 0.12065 -0.305054)
			(end 0.12065 -0.2794)
			(stroke
				(width 0.1)
				(type default)
			)
			(layer "B.Fab")
		)
		(fp_line
			(start -0.12065 -0.3048)
			(end -0.67945 -0.3048)
			(stroke
				(width 0.1)
				(type default)
			)
			(layer "B.Fab")
		)
		(fp_line
			(start -0.67945 -0.3048)
			(end -0.67945 0.3048)
			(stroke
				(width 0.1)
				(type default)
			)
			(layer "B.Fab")
		)
		(fp_line
			(start 0.12065 -0.2794)
			(end -0.12065 -0.2794)
			(stroke
				(width 0.1)
				(type default)
			)
			(layer "B.Fab")
		)
		(fp_line
			(start -0.12065 -0.2794)
			(end -0.12065 -0.3048)
			(stroke
				(width 0.1)
				(type default)
			)
			(layer "B.Fab")
		)
		(fp_line
			(start 0.12065 0.2794)
			(end 0.12065 0.3048)
			(stroke
				(width 0.1)
				(type default)
			)
			(layer "B.Fab")
		)
		(fp_line
			(start -0.120396 0.2794)
			(end 0.12065 0.2794)
			(stroke
				(width 0.1)
				(type default)
			)
			(layer "B.Fab")
		)
		(fp_line
			(start 0.67945 0.3048)
			(end 0.67945 -0.305054)
			(stroke
				(width 0.1)
				(type default)
			)
			(layer "B.Fab")
		)
		(fp_line
			(start 0.12065 0.3048)
			(end 0.67945 0.3048)
			(stroke
				(width 0.1)
				(type default)
			)
			(layer "B.Fab")
		)
		(fp_line
			(start -0.120396 0.3048)
			(end -0.120396 0.2794)
			(stroke
				(width 0.1)
				(type default)
			)
			(layer "B.Fab")
		)
		(fp_line
			(start -0.67945 0.3048)
			(end -0.120396 0.3048)
			(stroke
				(width 0.1)
				(type default)
			)
			(layer "B.Fab")
		)
		(pad "1" smd circle
			(at 0.40005 0 270)
			(size 0 0)
			(layers "B.Cu" "B.Mask" "B.Paste")
			(net "SMB_CPU1_SEC_R_SCL")
		)
		(pad "2" smd circle
			(at -0.40005 0 270)
			(size 0 0)
			(layers "B.Cu" "B.Mask" "B.Paste")
			(net "SMB_CPU1_SEC_SCL")
		)
	)
	(footprint ""
		(layer "B.Cu")
		(at 397.820642 -416.899344 90)
		(property "Reference" "C6613"
			(at 0 0 90)
			(layer "B.SilkS")
			(hide yes)
			(effects
				(font
					(size 1.27 1.27)
				)
				(justify mirror)
			)
		)
		(property "Value" ""
			(at 0 0 90)
			(layer "B.Fab")
			(effects
				(font
					(size 1.27 1.27)
				)
				(justify mirror)
			)
		)
		(duplicate_pad_numbers_are_jumpers no)
		(fp_line
			(start 0.299974 -0.150114)
			(end -0.299974 -0.150114)
			(stroke
				(width 0.1)
				(type default)
			)
			(layer "B.Fab")
		)
		(fp_line
			(start -0.299974 -0.150114)
			(end -0.299974 0.150114)
			(stroke
				(width 0.1)
				(type default)
			)
			(layer "B.Fab")
		)
		(fp_line
			(start 0.299974 0.150114)
			(end 0.299974 -0.150114)
			(stroke
				(width 0.1)
				(type default)
			)
			(layer "B.Fab")
		)
		(fp_line
			(start -0.299974 0.150114)
			(end 0.299974 0.150114)
			(stroke
				(width 0.1)
				(type default)
			)
			(layer "B.Fab")
		)
		(pad "1" smd rect
			(at 0.2667 0 270)
			(size 0.3048 0.381)
			(layers "B.Cu" "B.Mask" "B.Paste")
			(net "P5E_CPU0_P3_TX_BUF_C_DP<8>")
		)
		(pad "2" smd rect
			(at -0.2667 0 270)
			(size 0.3048 0.381)
			(layers "B.Cu" "B.Mask" "B.Paste")
			(net "P5E_CPU0_P3_TX_BUF_DP<8>")
		)
	)
	(footprint ""
		(layer "B.Cu")
		(at 231.943148 -322.84035 180)
		(property "Reference" "R1258"
			(at 0 0 0)
			(layer "B.SilkS")
			(hide yes)
			(effects
				(font
					(size 1.27 1.27)
				)
				(justify mirror)
			)
		)
		(property "Value" ""
			(at 0 0 0)
			(layer "B.Fab")
			(effects
				(font
					(size 1.27 1.27)
				)
				(justify mirror)
			)
		)
		(duplicate_pad_numbers_are_jumpers no)
		(fp_line
			(start 0.7874 0.4064)
			(end 0.7874 -0.4064)
			(stroke
				(width 0.1524)
				(type default)
			)
			(layer "B.SilkS")
		)
		(fp_line
			(start 0.7874 -0.4064)
			(end -0.7874 -0.4064)
			(stroke
				(width 0.1524)
				(type default)
			)
			(layer "B.SilkS")
		)
		(fp_line
			(start -0.7874 0.4064)
			(end 0.7874 0.4064)
			(stroke
				(width 0.1524)
				(type default)
			)
			(layer "B.SilkS")
		)
		(fp_line
			(start -0.7874 -0.4064)
			(end -0.7874 0.4064)
			(stroke
				(width 0.1524)
				(type default)
			)
			(layer "B.SilkS")
		)
		(fp_line
			(start 0.67945 0.3048)
			(end 0.67945 -0.305054)
			(stroke
				(width 0.1)
				(type default)
			)
			(layer "B.Fab")
		)
		(fp_line
			(start 0.67945 -0.305054)
			(end 0.12065 -0.305054)
			(stroke
				(width 0.1)
				(type default)
			)
			(layer "B.Fab")
		)
		(fp_line
			(start 0.12065 0.3048)
			(end 0.67945 0.3048)
			(stroke
				(width 0.1)
				(type default)
			)
			(layer "B.Fab")
		)
		(fp_line
			(start 0.12065 0.2794)
			(end 0.12065 0.3048)
			(stroke
				(width 0.1)
				(type default)
			)
			(layer "B.Fab")
		)
		(fp_line
			(start 0.12065 -0.2794)
			(end -0.12065 -0.2794)
			(stroke
				(width 0.1)
				(type default)
			)
			(layer "B.Fab")
		)
		(fp_line
			(start 0.12065 -0.305054)
			(end 0.12065 -0.2794)
			(stroke
				(width 0.1)
				(type default)
			)
			(layer "B.Fab")
		)
		(fp_line
			(start -0.120396 0.3048)
			(end -0.120396 0.2794)
			(stroke
				(width 0.1)
				(type default)
			)
			(layer "B.Fab")
		)
		(fp_line
			(start -0.120396 0.2794)
			(end 0.12065 0.2794)
			(stroke
				(width 0.1)
				(type default)
			)
			(layer "B.Fab")
		)
		(fp_line
			(start -0.12065 -0.2794)
			(end -0.12065 -0.3048)
			(stroke
				(width 0.1)
				(type default)
			)
			(layer "B.Fab")
		)
		(fp_line
			(start -0.12065 -0.3048)
			(end -0.67945 -0.3048)
			(stroke
				(width 0.1)
				(type default)
			)
			(layer "B.Fab")
		)
		(fp_line
			(start -0.67945 0.3048)
			(end -0.120396 0.3048)
			(stroke
				(width 0.1)
				(type default)
			)
			(layer "B.Fab")
		)
		(fp_line
			(start -0.67945 -0.3048)
			(end -0.67945 0.3048)
			(stroke
				(width 0.1)
				(type default)
			)
			(layer "B.Fab")
		)
		(pad "1" smd rect
			(at 0.40005 0 180)
			(size 0.4572 0.508)
			(layers "B.Cu" "B.Mask" "B.Paste")
			(net "P1V8_AUX_ADC")
		)
		(pad "2" smd rect
			(at -0.40005 0 180)
			(size 0.4572 0.508)
			(layers "B.Cu" "B.Mask" "B.Paste")
			(net "P1V8_AUX_ADC_MAM")
		)
	)
	(footprint ""
		(layer "B.Cu")
		(at 186.007502 -351.21342 90)
		(property "Reference" "PC515_1"
			(at 0 0 90)
			(layer "B.SilkS")
			(hide yes)
			(effects
				(font
					(size 1.27 1.27)
				)
				(justify mirror)
			)
		)
		(property "Value" ""
			(at 0 0 90)
			(layer "B.Fab")
			(effects
				(font
					(size 1.27 1.27)
				)
				(justify mirror)
			)
		)
		(duplicate_pad_numbers_are_jumpers no)
		(fp_line
			(start 1.524 -0.762)
			(end -1.524 -0.762)
			(stroke
				(width 0.1524)
				(type default)
			)
			(layer "B.SilkS")
		)
		(fp_line
			(start -1.524 -0.762)
			(end -1.524 0.762)
			(stroke
				(width 0.1524)
				(type default)
			)
			(layer "B.SilkS")
		)
		(fp_line
			(start 1.524 0.762)
			(end 1.524 -0.762)
			(stroke
				(width 0.1524)
				(type default)
			)
			(layer "B.SilkS")
		)
		(fp_line
			(start -1.524 0.762)
			(end 1.524 0.762)
			(stroke
				(width 0.1524)
				(type default)
			)
			(layer "B.SilkS")
		)
		(fp_line
			(start 1.1049 -0.724916)
			(end 1.1049 0.724916)
			(stroke
				(width 0.1)
				(type default)
			)
			(layer "B.Fab")
		)
		(fp_line
			(start -1.1049 -0.724916)
			(end 1.1049 -0.724916)
			(stroke
				(width 0.1)
				(type default)
			)
			(layer "B.Fab")
		)
		(fp_line
			(start 1.1049 0.724916)
			(end -1.1049 0.724916)
			(stroke
				(width 0.1)
				(type default)
			)
			(layer "B.Fab")
		)
		(fp_line
			(start -1.1049 0.724916)
			(end -1.1049 -0.724916)
			(stroke
				(width 0.1)
				(type default)
			)
			(layer "B.Fab")
		)
		(pad "1" smd rect
			(at 0.889 0 90)
			(size 1.016 1.27)
			(layers "B.Cu" "B.Mask" "B.Paste")
			(net "SW_P12V_AUX_PVDD11_S3_P1_FLT")
		)
		(pad "2" smd rect
			(at -0.889 0 90)
			(size 1.016 1.27)
			(layers "B.Cu" "B.Mask" "B.Paste")
			(net "GND")
		)
	)
	(footprint ""
		(layer "B.Cu")
		(at 216.20988 -53.177948)
		(property "Reference" "C2067"
			(at 0 0 0)
			(layer "B.SilkS")
			(hide yes)
			(effects
				(font
					(size 1.27 1.27)
				)
				(justify mirror)
			)
		)
		(property "Value" ""
			(at 0 0 0)
			(layer "B.Fab")
			(effects
				(font
					(size 1.27 1.27)
				)
				(justify mirror)
			)
		)
		(duplicate_pad_numbers_are_jumpers no)
		(fp_line
			(start -0.7874 -0.4064)
			(end -0.7874 0.4064)
			(stroke
				(width 0.1524)
				(type default)
			)
			(layer "B.SilkS")
		)
		(fp_line
			(start -0.7874 0.4064)
			(end 0.7874 0.4064)
			(stroke
				(width 0.1524)
				(type default)
			)
			(layer "B.SilkS")
		)
		(fp_line
			(start 0.7874 -0.4064)
			(end -0.7874 -0.4064)
			(stroke
				(width 0.1524)
				(type default)
			)
			(layer "B.SilkS")
		)
		(fp_line
			(start 0.7874 0.4064)
			(end 0.7874 -0.4064)
			(stroke
				(width 0.1524)
				(type default)
			)
			(layer "B.SilkS")
		)
		(fp_line
			(start -0.67945 -0.3048)
			(end -0.67945 0.3048)
			(stroke
				(width 0.1)
				(type default)
			)
			(layer "B.Fab")
		)
		(fp_line
			(start -0.67945 0.3048)
			(end -0.120396 0.3048)
			(stroke
				(width 0.1)
				(type default)
			)
			(layer "B.Fab")
		)
		(fp_line
			(start -0.12065 -0.3048)
			(end -0.67945 -0.3048)
			(stroke
				(width 0.1)
				(type default)
			)
			(layer "B.Fab")
		)
		(fp_line
			(start -0.12065 -0.2794)
			(end -0.12065 -0.3048)
			(stroke
				(width 0.1)
				(type default)
			)
			(layer "B.Fab")
		)
		(fp_line
			(start -0.120396 0.2794)
			(end 0.12065 0.2794)
			(stroke
				(width 0.1)
				(type default)
			)
			(layer "B.Fab")
		)
		(fp_line
			(start -0.120396 0.3048)
			(end -0.120396 0.2794)
			(stroke
				(width 0.1)
				(type default)
			)
			(layer "B.Fab")
		)
		(fp_line
			(start 0.12065 -0.305054)
			(end 0.12065 -0.2794)
			(stroke
				(width 0.1)
				(type default)
			)
			(layer "B.Fab")
		)
		(fp_line
			(start 0.12065 -0.2794)
			(end -0.12065 -0.2794)
			(stroke
				(width 0.1)
				(type default)
			)
			(layer "B.Fab")
		)
		(fp_line
			(start 0.12065 0.2794)
			(end 0.12065 0.3048)
			(stroke
				(width 0.1)
				(type default)
			)
			(layer "B.Fab")
		)
		(fp_line
			(start 0.12065 0.3048)
			(end 0.67945 0.3048)
			(stroke
				(width 0.1)
				(type default)
			)
			(layer "B.Fab")
		)
		(fp_line
			(start 0.67945 -0.305054)
			(end 0.12065 -0.305054)
			(stroke
				(width 0.1)
				(type default)
			)
			(layer "B.Fab")
		)
		(fp_line
			(start 0.67945 0.3048)
			(end 0.67945 -0.305054)
			(stroke
				(width 0.1)
				(type default)
			)
			(layer "B.Fab")
		)
		(pad "1" smd circle
			(at 0.40005 0 180)
			(size 0 0)
			(layers "B.Cu" "B.Mask" "B.Paste")
			(net "P3V3_AUX")
		)
		(pad "2" smd circle
			(at -0.40005 0 180)
			(size 0 0)
			(layers "B.Cu" "B.Mask" "B.Paste")
			(net "GND")
		)
	)
	(footprint ""
		(layer "B.Cu")
		(at 255.73736 -324.045072 180)
		(property "Reference" "C1084"
			(at 0 0 0)
			(layer "B.SilkS")
			(hide yes)
			(effects
				(font
					(size 1.27 1.27)
				)
				(justify mirror)
			)
		)
		(property "Value" ""
			(at 0 0 0)
			(layer "B.Fab")
			(effects
				(font
					(size 1.27 1.27)
				)
				(justify mirror)
			)
		)
		(duplicate_pad_numbers_are_jumpers no)
		(fp_line
			(start 0.7874 0.4064)
			(end 0.7874 -0.4064)
			(stroke
				(width 0.1524)
				(type default)
			)
			(layer "B.SilkS")
		)
		(fp_line
			(start 0.7874 -0.4064)
			(end -0.7874 -0.4064)
			(stroke
				(width 0.1524)
				(type default)
			)
			(layer "B.SilkS")
		)
		(fp_line
			(start -0.7874 0.4064)
			(end 0.7874 0.4064)
			(stroke
				(width 0.1524)
				(type default)
			)
			(layer "B.SilkS")
		)
		(fp_line
			(start -0.7874 -0.4064)
			(end -0.7874 0.4064)
			(stroke
				(width 0.1524)
				(type default)
			)
			(layer "B.SilkS")
		)
		(fp_line
			(start 0.67945 0.3048)
			(end 0.67945 -0.305054)
			(stroke
				(width 0.1)
				(type default)
			)
			(layer "B.Fab")
		)
		(fp_line
			(start 0.67945 -0.305054)
			(end 0.12065 -0.305054)
			(stroke
				(width 0.1)
				(type default)
			)
			(layer "B.Fab")
		)
		(fp_line
			(start 0.12065 0.3048)
			(end 0.67945 0.3048)
			(stroke
				(width 0.1)
				(type default)
			)
			(layer "B.Fab")
		)
		(fp_line
			(start 0.12065 0.2794)
			(end 0.12065 0.3048)
			(stroke
				(width 0.1)
				(type default)
			)
			(layer "B.Fab")
		)
		(fp_line
			(start 0.12065 -0.2794)
			(end -0.12065 -0.2794)
			(stroke
				(width 0.1)
				(type default)
			)
			(layer "B.Fab")
		)
		(fp_line
			(start 0.12065 -0.305054)
			(end 0.12065 -0.2794)
			(stroke
				(width 0.1)
				(type default)
			)
			(layer "B.Fab")
		)
		(fp_line
			(start -0.120396 0.3048)
			(end -0.120396 0.2794)
			(stroke
				(width 0.1)
				(type default)
			)
			(layer "B.Fab")
		)
		(fp_line
			(start -0.120396 0.2794)
			(end 0.12065 0.2794)
			(stroke
				(width 0.1)
				(type default)
			)
			(layer "B.Fab")
		)
		(fp_line
			(start -0.12065 -0.2794)
			(end -0.12065 -0.3048)
			(stroke
				(width 0.1)
				(type default)
			)
			(layer "B.Fab")
		)
		(fp_line
			(start -0.12065 -0.3048)
			(end -0.67945 -0.3048)
			(stroke
				(width 0.1)
				(type default)
			)
			(layer "B.Fab")
		)
		(fp_line
			(start -0.67945 0.3048)
			(end -0.120396 0.3048)
			(stroke
				(width 0.1)
				(type default)
			)
			(layer "B.Fab")
		)
		(fp_line
			(start -0.67945 -0.3048)
			(end -0.67945 0.3048)
			(stroke
				(width 0.1)
				(type default)
			)
			(layer "B.Fab")
		)
		(pad "1" smd circle
			(at 0.40005 0)
			(size 0 0)
			(layers "B.Cu" "B.Mask" "B.Paste")
			(net "P1V8_AUX_ADC_MAM")
		)
		(pad "2" smd circle
			(at -0.40005 0)
			(size 0 0)
			(layers "B.Cu" "B.Mask" "B.Paste")
			(net "GND")
		)
	)
)
